(kicad_pcb
	(version 20240108)
	(generator "pcbnew")
	(generator_version "8.0")
	(general
		(thickness 1.586)
		(legacy_teardrops no)
	)
	(paper "A4")
	(title_block
		(title "GMSL Serializer")
		(date "2024-11-27")
		(rev "1.1.1")
		(company "Antmicro Ltd")
		(comment 1 "www.antmicro.com")
		(comment 9 "footprints 88-92 of 117")
	)
	(layers
		(0 "F.Cu" signal)
		(1 "In1.Cu" power)
		(2 "In2.Cu" power)
		(31 "B.Cu" signal)
		(32 "B.Adhes" user "B.Adhesive")
		(33 "F.Adhes" user "F.Adhesive")
		(34 "B.Paste" user)
		(35 "F.Paste" user)
		(36 "B.SilkS" user "B.Silkscreen")
		(37 "F.SilkS" user "F.Silkscreen")
		(38 "B.Mask" user)
		(39 "F.Mask" user)
		(40 "Dwgs.User" user "User.Drawings")
		(41 "Cmts.User" user "User.Comments")
		(42 "Eco1.User" user "User.Eco1")
		(43 "Eco2.User" user "User.Eco2")
		(44 "Edge.Cuts" user)
		(45 "Margin" user)
		(46 "B.CrtYd" user "B.Courtyard")
		(47 "F.CrtYd" user "F.Courtyard")
		(48 "B.Fab" user)
		(49 "F.Fab" user)
	)
	(footprint "antmicro-footprints:C_0402_1005Metric"
		(layer "F.Cu")
		(at 151.032448 98.81 45)
		(descr "Capacitor SMD 0402")
		(tags "capacitor SMD 0402")
		(property "Reference" "C30"
			(at 2.226539 0.456738 45)
			(layer "F.SilkS")
			(effects
				(font
					(size 0.7 0.7)
					(thickness 0.15)
				)
				(justify left bottom)
			)
		)
		(property "Value" "C_100n_0402"
			(at -1.022927 2.155213 45)
			(layer "F.Fab")
			(effects
				(font
					(size 0.7 0.7)
					(thickness 0.15)
				)
				(justify left bottom)
			)
		)
		(property "Footprint" "antmicro-footprints:C_0402_1005Metric"
			(at 0 0 45)
			(layer "F.Fab")
			(hide yes)
			(effects
				(font
					(size 1.27 1.27)
					(thickness 0.15)
				)
			)
		)
		(property "Datasheet" "https://www.murata.com/products/productdetail?partno=GRM155R61H104KE14%23"
			(at 0 0 45)
			(layer "F.Fab")
			(hide yes)
			(effects
				(font
					(size 1.27 1.27)
					(thickness 0.15)
				)
			)
		)
		(property "Author" "Antmicro"
			(at 114.105601 -77.855289 0)
			(layer "F.Fab")
			(hide yes)
			(effects
				(font
					(size 1 1)
					(thickness 0.15)
				)
			)
		)
		(property "Dielectric" "X5R"
			(at 114.105601 -77.855289 0)
			(layer "F.Fab")
			(hide yes)
			(effects
				(font
					(size 1 1)
					(thickness 0.15)
				)
			)
		)
		(property "License" "Apache-2.0"
			(at 114.105601 -77.855289 0)
			(layer "F.Fab")
			(hide yes)
			(effects
				(font
					(size 1 1)
					(thickness 0.15)
				)
			)
		)
		(property "MPN" "GRM155R61H104KE14D"
			(at 114.105601 -77.855289 0)
			(layer "F.Fab")
			(hide yes)
			(effects
				(font
					(size 1 1)
					(thickness 0.15)
				)
			)
		)
		(property "Manufacturer" "Murata"
			(at 114.105601 -77.855289 0)
			(layer "F.Fab")
			(hide yes)
			(effects
				(font
					(size 1 1)
					(thickness 0.15)
				)
			)
		)
		(property "Val" "100n"
			(at 114.105601 -77.855289 0)
			(layer "F.Fab")
			(hide yes)
			(effects
				(font
					(size 1 1)
					(thickness 0.15)
				)
			)
		)
		(property "Voltage" "50V"
			(at 114.105601 -77.855289 0)
			(layer "F.Fab")
			(hide yes)
			(effects
				(font
					(size 1 1)
					(thickness 0.15)
				)
			)
		)
		(sheetname "Serializer")
		(sheetfile "serializer.kicad_sch")
		(attr smd)
		(fp_poly
			(pts
				(xy -0.925 -0.47) (xy 0.925 -0.47) (xy 0.925 0.47) (xy -0.925 0.47)
			)
			(stroke
				(width 0.05)
				(type default)
			)
			(fill none)
			(layer "F.CrtYd")
		)
		(fp_line
			(start -0.494 -0.25)
			(end 0.504 -0.25)
			(stroke
				(width 0.15)
				(type solid)
			)
			(layer "F.Fab")
		)
		(fp_line
			(start -0.494 0.248)
			(end -0.494 -0.25)
			(stroke
				(width 0.15)
				(type solid)
			)
			(layer "F.Fab")
		)
		(fp_line
			(start 0.504 -0.25)
			(end 0.504 0.248)
			(stroke
				(width 0.15)
				(type solid)
			)
			(layer "F.Fab")
		)
		(fp_line
			(start 0.504 0.248)
			(end -0.494 0.248)
			(stroke
				(width 0.15)
				(type solid)
			)
			(layer "F.Fab")
		)
		(fp_text user "${REFERENCE}"
			(at -0.939 4.599 45)
			(layer "F.Fab")
			(hide yes)
			(effects
				(font
					(size 0.7 0.7)
					(thickness 0.15)
				)
				(justify left bottom)
			)
		)
		(fp_text user "Author: Antmicro"
			(at -0.939 3.399 45)
			(layer "F.Fab")
			(hide yes)
			(effects
				(font
					(size 0.7 0.7)
					(thickness 0.15)
				)
				(justify left bottom)
			)
		)
		(fp_text user "License: Apache-2.0"
			(at -0.939 5.799 45)
			(layer "F.Fab")
			(hide yes)
			(effects
				(font
					(size 0.7 0.7)
					(thickness 0.15)
				)
				(justify left bottom)
			)
		)
		(pad "1" smd roundrect
			(at -0.48 0 45)
			(size 0.59 0.64)
			(layers "F.Cu" "F.Paste" "F.Mask")
			(roundrect_rratio 0.25)
			(net 17 "Net-(U6-SIOP)")
			(pintype "passive")
		)
		(pad "2" smd roundrect
			(at 0.48 0 45)
			(size 0.59 0.64)
			(layers "F.Cu" "F.Paste" "F.Mask")
			(roundrect_rratio 0.25)
			(net 18 "/GMSL Connector/SIO_P")
			(pintype "passive")
		)
	)
	(footprint "antmicro-footprints:R_0402_1005Metric"
		(layer "F.Cu")
		(at 132.17 80.15)
		(descr "Resistor SMD 0402")
		(tags "resistor SMD 0402")
		(property "Reference" "R10"
			(at -1.1 -0.6 0)
			(layer "F.SilkS")
			(effects
				(font
					(size 0.7 0.7)
					(thickness 0.15)
				)
				(justify left bottom)
			)
		)
		(property "Value" "R_10k_0402"
			(at -1.011843 1.772047 0)
			(layer "F.Fab")
			(effects
				(font
					(size 0.7 0.7)
					(thickness 0.15)
				)
				(justify left bottom)
			)
		)
		(property "Footprint" "antmicro-footprints:R_0402_1005Metric"
			(at 0 0 0)
			(layer "F.Fab")
			(hide yes)
			(effects
				(font
					(size 1.27 1.27)
					(thickness 0.15)
				)
			)
		)
		(property "Datasheet" "https://www.bourns.com/docs/product-datasheets/cr.pdf"
			(at 0 0 0)
			(layer "F.Fab")
			(hide yes)
			(effects
				(font
					(size 1.27 1.27)
					(thickness 0.15)
				)
			)
		)
		(property "Author" "Antmicro"
			(at 0 0 0)
			(layer "F.Fab")
			(hide yes)
			(effects
				(font
					(size 1 1)
					(thickness 0.15)
				)
			)
		)
		(property "License" "Apache-2.0"
			(at 0 0 0)
			(layer "F.Fab")
			(hide yes)
			(effects
				(font
					(size 1 1)
					(thickness 0.15)
				)
			)
		)
		(property "MPN" "CR0402-FX-1002GLF"
			(at 0 0 0)
			(layer "F.Fab")
			(hide yes)
			(effects
				(font
					(size 1 1)
					(thickness 0.15)
				)
			)
		)
		(property "Manufacturer" "Bourns"
			(at 0 0 0)
			(layer "F.Fab")
			(hide yes)
			(effects
				(font
					(size 1 1)
					(thickness 0.15)
				)
			)
		)
		(property "Tolerance" "1%"
			(at 0 0 0)
			(layer "F.Fab")
			(hide yes)
			(effects
				(font
					(size 1 1)
					(thickness 0.15)
				)
			)
		)
		(property "Val" "10k"
			(at 0 0 0)
			(layer "F.Fab")
			(hide yes)
			(effects
				(font
					(size 1 1)
					(thickness 0.15)
				)
			)
		)
		(sheetname "Supply")
		(sheetfile "supply.kicad_sch")
		(attr smd)
		(fp_rect
			(start -0.925 -0.47)
			(end 0.925 0.47)
			(stroke
				(width 0.05)
				(type default)
			)
			(fill none)
			(layer "F.CrtYd")
		)
		(fp_rect
			(start -0.5 -0.25)
			(end 0.5 0.25)
			(stroke
				(width 0.15)
				(type solid)
			)
			(fill none)
			(layer "F.Fab")
		)
		(fp_text user "License: Apache-2.0"
			(at -0.95 5.169 0)
			(layer "F.Fab")
			(hide yes)
			(effects
				(font
					(size 0.7 0.7)
					(thickness 0.15)
				)
				(justify left bottom)
			)
		)
		(fp_text user "${REFERENCE}"
			(at -0.95 3.168 0)
			(layer "F.Fab")
			(hide yes)
			(effects
				(font
					(size 0.7 0.7)
					(thickness 0.15)
				)
				(justify left bottom)
			)
		)
		(fp_text user "Author: Antmicro"
			(at -0.95 4.169 0)
			(layer "F.Fab")
			(hide yes)
			(effects
				(font
					(size 0.7 0.7)
					(thickness 0.15)
				)
				(justify left bottom)
			)
		)
		(pad "1" smd roundrect
			(at -0.48 0)
			(size 0.59 0.64)
			(layers "F.Cu" "F.Paste" "F.Mask")
			(roundrect_rratio 0.25)
			(net 1 "GND")
			(pintype "passive")
		)
		(pad "2" smd roundrect
			(at 0.48 0)
			(size 0.59 0.64)
			(layers "F.Cu" "F.Paste" "F.Mask")
			(roundrect_rratio 0.25)
			(net 64 "/Supply/FB_5V")
			(pintype "passive")
		)
	)
	(footprint "antmicro-footprints:R_0402_1005Metric"
		(layer "F.Cu")
		(at 133.1 111.98 180)
		(descr "Resistor SMD 0402")
		(tags "resistor SMD 0402")
		(property "Reference" "R5"
			(at -2.566667 5.646668 0)
			(layer "F.SilkS")
			(effects
				(font
					(size 0.7 0.7)
					(thickness 0.15)
				)
				(justify right bottom)
			)
		)
		(property "Value" "R_4k7_0402"
			(at -1.011843 1.772047 0)
			(layer "F.Fab")
			(effects
				(font
					(size 0.7 0.7)
					(thickness 0.15)
				)
				(justify right bottom)
			)
		)
		(property "Footprint" "antmicro-footprints:R_0402_1005Metric"
			(at 0 0 180)
			(layer "F.Fab")
			(hide yes)
			(effects
				(font
					(size 1.27 1.27)
					(thickness 0.15)
				)
			)
		)
		(property "Datasheet" "https://www.bourns.com/docs/product-datasheets/cr.pdf"
			(at 0 0 180)
			(layer "F.Fab")
			(hide yes)
			(effects
				(font
					(size 1.27 1.27)
					(thickness 0.15)
				)
			)
		)
		(property "Author" "Antmicro"
			(at 266.2 223.96 0)
			(layer "F.Fab")
			(hide yes)
			(effects
				(font
					(size 1 1)
					(thickness 0.15)
				)
			)
		)
		(property "License" "Apache-2.0"
			(at 266.2 223.96 0)
			(layer "F.Fab")
			(hide yes)
			(effects
				(font
					(size 1 1)
					(thickness 0.15)
				)
			)
		)
		(property "MPN" "CR0402-FX-4701GLF"
			(at 266.2 223.96 0)
			(layer "F.Fab")
			(hide yes)
			(effects
				(font
					(size 1 1)
					(thickness 0.15)
				)
			)
		)
		(property "Manufacturer" "Bourns"
			(at 266.2 223.96 0)
			(layer "F.Fab")
			(hide yes)
			(effects
				(font
					(size 1 1)
					(thickness 0.15)
				)
			)
		)
		(property "Tolerance" "1%"
			(at 266.2 223.96 0)
			(layer "F.Fab")
			(hide yes)
			(effects
				(font
					(size 1 1)
					(thickness 0.15)
				)
			)
		)
		(property "Val" "4k7"
			(at 266.2 223.96 0)
			(layer "F.Fab")
			(hide yes)
			(effects
				(font
					(size 1 1)
					(thickness 0.15)
				)
			)
		)
		(sheetname "CSI Connector")
		(sheetfile "CSI.kicad_sch")
		(attr smd)
		(fp_rect
			(start -0.925 -0.47)
			(end 0.925 0.47)
			(stroke
				(width 0.05)
				(type default)
			)
			(fill none)
			(layer "F.CrtYd")
		)
		(fp_rect
			(start -0.5 -0.25)
			(end 0.5 0.25)
			(stroke
				(width 0.15)
				(type solid)
			)
			(fill none)
			(layer "F.Fab")
		)
		(fp_text user "Author: Antmicro"
			(at -0.95 4.169 0)
			(layer "F.Fab")
			(hide yes)
			(effects
				(font
					(size 0.7 0.7)
					(thickness 0.15)
				)
				(justify right bottom)
			)
		)
		(fp_text user "License: Apache-2.0"
			(at -0.95 5.169 0)
			(layer "F.Fab")
			(hide yes)
			(effects
				(font
					(size 0.7 0.7)
					(thickness 0.15)
				)
				(justify right bottom)
			)
		)
		(fp_text user "${REFERENCE}"
			(at -0.95 3.168 0)
			(layer "F.Fab")
			(hide yes)
			(effects
				(font
					(size 0.7 0.7)
					(thickness 0.15)
				)
				(justify right bottom)
			)
		)
		(pad "1" smd roundrect
			(at -0.48 0 180)
			(size 0.59 0.64)
			(layers "F.Cu" "F.Paste" "F.Mask")
			(roundrect_rratio 0.25)
			(net 88 "/CSI Connector/I2C.SDA")
			(pintype "passive")
		)
		(pad "2" smd roundrect
			(at 0.48 0 180)
			(size 0.59 0.64)
			(layers "F.Cu" "F.Paste" "F.Mask")
			(roundrect_rratio 0.25)
			(net 10 "+3V3")
			(pintype "passive")
		)
	)
	(footprint "antmicro-footprints:R_0402_1005Metric"
		(layer "F.Cu")
		(at 133.101 109.884)
		(descr "Resistor SMD 0402")
		(tags "resistor SMD 0402")
		(property "Reference" "R24"
			(at 1.049 -5.434 0)
			(layer "F.SilkS")
			(effects
				(font
					(size 0.7 0.7)
					(thickness 0.15)
				)
				(justify left bottom)
			)
		)
		(property "Value" "R_100R_0402"
			(at -1.011843 1.772047 0)
			(layer "F.Fab")
			(effects
				(font
					(size 0.7 0.7)
					(thickness 0.15)
				)
				(justify left bottom)
			)
		)
		(property "Footprint" "antmicro-footprints:R_0402_1005Metric"
			(at 0 0 0)
			(layer "F.Fab")
			(hide yes)
			(effects
				(font
					(size 1.27 1.27)
					(thickness 0.15)
				)
			)
		)
		(property "Datasheet" "https://www.bourns.com/docs/product-datasheets/cr.pdf"
			(at 0 0 0)
			(layer "F.Fab")
			(hide yes)
			(effects
				(font
					(size 1.27 1.27)
					(thickness 0.15)
				)
			)
		)
		(property "Author" "Antmicro"
			(at 0 0 0)
			(layer "F.Fab")
			(hide yes)
			(effects
				(font
					(size 1 1)
					(thickness 0.15)
				)
			)
		)
		(property "License" "Apache-2.0"
			(at 0 0 0)
			(layer "F.Fab")
			(hide yes)
			(effects
				(font
					(size 1 1)
					(thickness 0.15)
				)
			)
		)
		(property "MPN" "CR0402-FX-1000GLF"
			(at 0 0 0)
			(layer "F.Fab")
			(hide yes)
			(effects
				(font
					(size 1 1)
					(thickness 0.15)
				)
			)
		)
		(property "Manufacturer" "Bourns"
			(at 0 0 0)
			(layer "F.Fab")
			(hide yes)
			(effects
				(font
					(size 1 1)
					(thickness 0.15)
				)
			)
		)
		(property "Tolerance" "1%"
			(at 0 0 0)
			(layer "F.Fab")
			(hide yes)
			(effects
				(font
					(size 1 1)
					(thickness 0.15)
				)
			)
		)
		(property "Val" "100R"
			(at 0 0 0)
			(layer "F.Fab")
			(hide yes)
			(effects
				(font
					(size 1 1)
					(thickness 0.15)
				)
			)
		)
		(sheetname "CSI Connector")
		(sheetfile "CSI.kicad_sch")
		(attr smd)
		(fp_rect
			(start -0.925 -0.47)
			(end 0.925 0.47)
			(stroke
				(width 0.05)
				(type default)
			)
			(fill none)
			(layer "F.CrtYd")
		)
		(fp_rect
			(start -0.5 -0.25)
			(end 0.5 0.25)
			(stroke
				(width 0.15)
				(type solid)
			)
			(fill none)
			(layer "F.Fab")
		)
		(fp_text user "Author: Antmicro"
			(at -0.95 4.169 0)
			(layer "F.Fab")
			(hide yes)
			(effects
				(font
					(size 0.7 0.7)
					(thickness 0.15)
				)
				(justify left bottom)
			)
		)
		(fp_text user "${REFERENCE}"
			(at -0.95 3.168 0)
			(layer "F.Fab")
			(hide yes)
			(effects
				(font
					(size 0.7 0.7)
					(thickness 0.15)
				)
				(justify left bottom)
			)
		)
		(fp_text user "License: Apache-2.0"
			(at -0.95 5.169 0)
			(layer "F.Fab")
			(hide yes)
			(effects
				(font
					(size 0.7 0.7)
					(thickness 0.15)
				)
				(justify left bottom)
			)
		)
		(pad "1" smd roundrect
			(at -0.48 0)
			(size 0.59 0.64)
			(layers "F.Cu" "F.Paste" "F.Mask")
			(roundrect_rratio 0.25)
			(net 36 "/CSI Connector/SDA_CAM1")
			(pintype "passive")
		)
		(pad "2" smd roundrect
			(at 0.48 0)
			(size 0.59 0.64)
			(layers "F.Cu" "F.Paste" "F.Mask")
			(roundrect_rratio 0.25)
			(net 88 "/CSI Connector/I2C.SDA")
			(pintype "passive")
		)
	)
	(footprint "antmicro-footprints:R_0402_1005Metric"
		(layer "F.Cu")
		(at 143.69 79.700142 90)
		(descr "Resistor SMD 0402")
		(tags "resistor SMD 0402")
		(property "Reference" "R42"
			(at -0.989858 -0.94 90)
			(layer "F.SilkS")
			(effects
				(font
					(size 0.7 0.7)
					(thickness 0.15)
				)
				(justify left bottom)
			)
		)
		(property "Value" "R_10k_0402"
			(at -1.011843 1.772047 90)
			(layer "F.Fab")
			(effects
				(font
					(size 0.7 0.7)
					(thickness 0.15)
				)
				(justify left bottom)
			)
		)
		(property "Footprint" "antmicro-footprints:R_0402_1005Metric"
			(at 0 0 90)
			(layer "F.Fab")
			(hide yes)
			(effects
				(font
					(size 1.27 1.27)
					(thickness 0.15)
				)
			)
		)
		(property "Datasheet" "https://www.bourns.com/docs/product-datasheets/cr.pdf"
			(at 0 0 90)
			(layer "F.Fab")
			(hide yes)
			(effects
				(font
					(size 1.27 1.27)
					(thickness 0.15)
				)
			)
		)
		(property "MPN" "CR0402-FX-1002GLF"
			(at 0 0 90)
			(unlocked yes)
			(layer "F.Fab")
			(hide yes)
			(effects
				(font
					(size 1 1)
					(thickness 0.15)
				)
			)
		)
		(property "Manufacturer" "Bourns"
			(at 0 0 90)
			(unlocked yes)
			(layer "F.Fab")
			(hide yes)
			(effects
				(font
					(size 1 1)
					(thickness 0.15)
				)
			)
		)
		(property "License" "Apache-2.0"
			(at 0 0 90)
			(unlocked yes)
			(layer "F.Fab")
			(hide yes)
			(effects
				(font
					(size 1 1)
					(thickness 0.15)
				)
			)
		)
		(property "Author" "Antmicro"
			(at 0 0 90)
			(unlocked yes)
			(layer "F.Fab")
			(hide yes)
			(effects
				(font
					(size 1 1)
					(thickness 0.15)
				)
			)
		)
		(property "Val" "10k"
			(at 0 0 90)
			(unlocked yes)
			(layer "F.Fab")
			(hide yes)
			(effects
				(font
					(size 1 1)
					(thickness 0.15)
				)
			)
		)
		(property "Tolerance" "1%"
			(at 0 0 90)
			(unlocked yes)
			(layer "F.Fab")
			(hide yes)
			(effects
				(font
					(size 1 1)
					(thickness 0.15)
				)
			)
		)
		(sheetname "Supply")
		(sheetfile "supply.kicad_sch")
		(attr smd)
		(fp_rect
			(start -0.925 -0.47)
			(end 0.925 0.47)
			(stroke
				(width 0.05)
				(type default)
			)
			(fill none)
			(layer "F.CrtYd")
		)
		(fp_rect
			(start -0.5 -0.25)
			(end 0.5 0.25)
			(stroke
				(width 0.15)
				(type solid)
			)
			(fill none)
			(layer "F.Fab")
		)
		(fp_text user "License: Apache-2.0"
			(at -0.95 5.169 90)
			(layer "F.Fab")
			(hide yes)
			(effects
				(font
					(size 0.7 0.7)
					(thickness 0.15)
				)
				(justify left bottom)
			)
		)
		(fp_text user "${REFERENCE}"
			(at -0.95 3.168 90)
			(layer "F.Fab")
			(hide yes)
			(effects
				(font
					(size 0.7 0.7)
					(thickness 0.15)
				)
				(justify left bottom)
			)
		)
		(fp_text user "Author: Antmicro"
			(at -0.95 4.169 90)
			(layer "F.Fab")
			(hide yes)
			(effects
				(font
					(size 0.7 0.7)
					(thickness 0.15)
				)
				(justify left bottom)
			)
		)
		(pad "1" smd roundrect
			(at -0.48 0 90)
			(size 0.59 0.64)
			(layers "F.Cu" "F.Paste" "F.Mask")
			(roundrect_rratio 0.25)
			(net 1 "GND")
			(pintype "passive")
		)
		(pad "2" smd roundrect
			(at 0.48 0 90)
			(size 0.59 0.64)
			(layers "F.Cu" "F.Paste" "F.Mask")
			(roundrect_rratio 0.25)
			(net 97 "/Supply/EN_3V3")
			(pintype "passive")
		)
	)
)
